FILE_TYPE = MACRO_DRAWING;
SET COLOR_WIRE YELLOW;
SET COLOR_PROP MONO;
SET COLOR_DOT WHITE;
SET COLOR_ARC YELLOW;
SET COLOR_BODY GREEN;
SET COLOR_NOTE MONO;
SET PROP_DISPLAY VALUE;
SET PAGE_NUMBER P1;
FORCEADD INTEL_CORP_BPAGE..1
(0 0);
FORCEPROP 2 LAST CUSTOM_TXT_CDS <XR_PAGE_TITLE>
J 0
(-7890 5250);
DISPLAY 0.638298 (-7890 5250);
PAINT PINK (-7890 5250);
DISPLAY INVISIBLE (-7890 5250);
FORCEPROP 2 LAST CUSTOM_TXT_CDS <CON_LAST_MODIFIED>
J 0
(-1925 350);
PAINT ORANGE (-1925 350);
FORCEPROP 2 LAST CUSTOM_TXT_CDS <CURRENT_DESIGN_SHEET> OF <TOTAL_DESIGN_SHEETS>
J 0
(-500 25);
PAINT ORANGE (-500 25);
FORCEPROP 1 LAST SCH_ADDRESS1 2200 Mission College Blvd.
J 0
(-3975 125);
DISPLAY 0.617021 (-3975 125);
PAINT GREEN (-3975 125);
FORCEPROP 1 LAST SCH_ADDRESS3 Santa Clara, CA 95052-8119
J 0
(-3975 25);
DISPLAY 0.617021 (-3975 25);
PAINT GREEN (-3975 25);
FORCEPROP 1 LAST SCH_REV 2.420
J 0
(-250 150);
DISPLAY 0.978723 (-250 150);
PAINT YELLOW (-250 150);
FORCEPROP 1 LAST SCH_NUMBER H4694802
J 0
(-1300 150);
DISPLAY 1.212766 (-1300 150);
PAINT YELLOW (-1300 150);
FORCEPROP 1 LAST SCH_ADDRESS2 P.O. BOX 58119
J 0
(-3975 75);
DISPLAY 0.617021 (-3975 75);
PAINT GREEN (-3975 75);
FORCEPROP 1 LAST SCH_DEPT BESD
J 1
(-4450 100);
DISPLAY 1.212766 (-4450 100);
PAINT YELLOW (-4450 100);
FORCEPROP 1 LAST COMMENT_BODY TRUE
J 0
(12 12);
DISPLAY 0.468085 (12 12);
PAINT GREEN (12 12);
DISPLAY INVISIBLE (12 12);
FORCEPROP 2 LAST PAGE_BORDER TRUE
J 0
(-7890 5250);
DISPLAY 0.638298 (-7890 5250);
PAINT PINK (-7890 5250);
DISPLAY INVISIBLE (-7890 5250);
FORCEPROP 2 LAST CDS_LIB mstr_symbols
J 0
(0 0);
PAINT ORANGE (0 0);
DISPLAY INVISIBLE (0 0);
FORCEPROP 1 LAST SCH_TITLE TITLE
J 0
(-7950 50);
DISPLAY 2.468085 (-7950 50);
PAINT ORANGE (-7950 50);
DISPLAY INVISIBLE (-7950 50);
FORCEPROP 1 LAST CDS_CON_LAST_MODIFIED Tue Dec 01 11:47:54 2015
J 0
(-1425 325);
PAINT ORANGE (-1425 325);
DISPLAY INVISIBLE (-1425 325);
FORCEPROP 2 LAST CDS_XR_PAGE_TITLE CR-1 : @BASEBOARD_FAB2_LIB.BASEBOARD_FAB2(SCH_1):PAGE1
J 0
(-7890 5250);
DISPLAY 0.638298 (-7890 5250);
PAINT PINK (-7890 5250);
DISPLAY INVISIBLE (-7890 5250);
FORCENOTE
$CDS_IMAGE|clipboard_1.jpg|4097|2146
(-3324 2577) 0;
DISPLAY CENTER (-3324 2577);
PAINT MONO (-3324 2577);
FORCENOTE
TIOGA PASS
(-7075 3000) 0;
DISPLAY LEFT (-7075 3000);
DISPLAY 3.148936 (-7075 3000);
PAINT PURPLE (-7075 3000);
FORCENOTE
PBA: H46948-200
(-7000 2675) 0;
DISPLAY LEFT (-7000 2675);
DISPLAY 2.000000 (-7000 2675);
PAINT PURPLE (-7000 2675);
FORCENOTE
PB: H46947-002
(-6950 2525) 0;
DISPLAY LEFT (-6950 2525);
DISPLAY 2.000000 (-6950 2525);
PAINT PURPLE (-6950 2525);
QUIT
